# T6G (Grand Teton) — schematic netlist excerpt (pin names and nets, part order shuffled) for the footprints in the layout excerpt that follows; sources: Cadence DE-HDL packaged netlist, KiCad conversion of 04192023_DAF0TMB3IC0_F0TG_MB_C_brd_V02_OCP.brd

PR2515  Q_RES  10 1% CHIP  pkg 0402LF  page 266 : A = P12V_HSC_ADC_N ; B = P12V_HSC_SENSE2_R1_N
R1798  Q_RES  0 5% CHIP  pkg 0402LF  page 150 : A = SCM_ROT_CPU_RST_R_N ; B = SCM_ROT_CPU_RST_N

(kicad_pcb
	(version 20260206)
	(generator "pcbnew")
	(generator_version "10.0")
	(general
		(thickness 1.6)
		(legacy_teardrops no)
	)
	(paper "A4")
	(title_block
		(title "04192023_DAF0TMB3IC0_F0TG_MB_C_brd_V02_OCP.brd")
		(comment 1 "Grand Teton / footprints 6792-6793 of 8354")
	)
	(layers
		(0 "F.Cu" signal "TOP")
		(4 "In1.Cu" signal "GND")
		(6 "In2.Cu" signal "IN1")
		(8 "In3.Cu" signal "GND1")
		(10 "In4.Cu" signal "IN2")
		(12 "In5.Cu" signal "GND2")
		(14 "In6.Cu" signal "IN3")
		(16 "In7.Cu" signal "GND3")
		(18 "In8.Cu" signal "VCC")
		(20 "In9.Cu" signal "VCC1")
		(22 "In10.Cu" signal "GND4")
		(24 "In11.Cu" signal "IN4")
		(26 "In12.Cu" signal "GND5")
		(28 "In13.Cu" signal "IN5")
		(30 "In14.Cu" signal "GND6")
		(32 "In15.Cu" signal "IN6")
		(34 "In16.Cu" signal "GND7")
		(2 "B.Cu" signal "BOTTOM")
		(9 "F.Adhes" user "F.Adhesive")
		(11 "B.Adhes" user "B.Adhesive")
		(13 "F.Paste" user "Package Geometry/Pastemask Top")
		(15 "B.Paste" user "Package Geometry/Pastemask Bottom")
		(5 "F.SilkS" user "Ref Des/Silkscreen Top")
		(7 "B.SilkS" user "Ref Des/Silkscreen Bottom")
		(1 "F.Mask" user "Board Geometry/Soldermask Top")
		(3 "B.Mask" user "Board Geometry/Soldermask Bottom")
		(17 "Dwgs.User" user "User.Drawings")
		(19 "Cmts.User" user "User.Comments")
		(21 "Eco1.User" user "User.Eco1")
		(23 "Eco2.User" user "User.Eco2")
		(25 "Edge.Cuts" user "Board Geometry/Outline")
		(27 "Margin" user)
		(31 "F.CrtYd" user "Package Geometry/Place Bound Top")
		(29 "B.CrtYd" user "Package Geometry/Place Bound Bottom")
		(35 "F.Fab" user "Ref Des/Assembly Top")
		(33 "B.Fab" user "Ref Des/Assembly Bottom")
	)
	(footprint ""
		(layer "B.Cu")
		(at 139.679426 -9.058148 -90)
		(property "Reference" "R1798"
			(at 0 0 90)
			(layer "B.SilkS")
			(hide yes)
			(effects
				(font
					(size 1.27 1.27)
				)
				(justify mirror)
			)
		)
		(property "Value" ""
			(at 0 0 90)
			(layer "B.Fab")
			(effects
				(font
					(size 1.27 1.27)
				)
				(justify mirror)
			)
		)
		(duplicate_pad_numbers_are_jumpers no)
		(fp_line
			(start -0.7874 0.4064)
			(end 0.7874 0.4064)
			(stroke
				(width 0.1524)
				(type default)
			)
			(layer "B.SilkS")
		)
		(fp_line
			(start 0.7874 0.4064)
			(end 0.7874 -0.4064)
			(stroke
				(width 0.1524)
				(type default)
			)
			(layer "B.SilkS")
		)
		(fp_line
			(start -0.7874 -0.4064)
			(end -0.7874 0.4064)
			(stroke
				(width 0.1524)
				(type default)
			)
			(layer "B.SilkS")
		)
		(fp_line
			(start 0.7874 -0.4064)
			(end -0.7874 -0.4064)
			(stroke
				(width 0.1524)
				(type default)
			)
			(layer "B.SilkS")
		)
		(fp_line
			(start -0.67945 0.3048)
			(end -0.120396 0.3048)
			(stroke
				(width 0.1)
				(type default)
			)
			(layer "B.Fab")
		)
		(fp_line
			(start -0.120396 0.3048)
			(end -0.120396 0.2794)
			(stroke
				(width 0.1)
				(type default)
			)
			(layer "B.Fab")
		)
		(fp_line
			(start 0.12065 0.3048)
			(end 0.67945 0.3048)
			(stroke
				(width 0.1)
				(type default)
			)
			(layer "B.Fab")
		)
		(fp_line
			(start 0.67945 0.3048)
			(end 0.67945 -0.305054)
			(stroke
				(width 0.1)
				(type default)
			)
			(layer "B.Fab")
		)
		(fp_line
			(start -0.120396 0.2794)
			(end 0.12065 0.2794)
			(stroke
				(width 0.1)
				(type default)
			)
			(layer "B.Fab")
		)
		(fp_line
			(start 0.12065 0.2794)
			(end 0.12065 0.3048)
			(stroke
				(width 0.1)
				(type default)
			)
			(layer "B.Fab")
		)
		(fp_line
			(start -0.12065 -0.2794)
			(end -0.12065 -0.3048)
			(stroke
				(width 0.1)
				(type default)
			)
			(layer "B.Fab")
		)
		(fp_line
			(start 0.12065 -0.2794)
			(end -0.12065 -0.2794)
			(stroke
				(width 0.1)
				(type default)
			)
			(layer "B.Fab")
		)
		(fp_line
			(start -0.67945 -0.3048)
			(end -0.67945 0.3048)
			(stroke
				(width 0.1)
				(type default)
			)
			(layer "B.Fab")
		)
		(fp_line
			(start -0.12065 -0.3048)
			(end -0.67945 -0.3048)
			(stroke
				(width 0.1)
				(type default)
			)
			(layer "B.Fab")
		)
		(fp_line
			(start 0.12065 -0.305054)
			(end 0.12065 -0.2794)
			(stroke
				(width 0.1)
				(type default)
			)
			(layer "B.Fab")
		)
		(fp_line
			(start 0.67945 -0.305054)
			(end 0.12065 -0.305054)
			(stroke
				(width 0.1)
				(type default)
			)
			(layer "B.Fab")
		)
		(pad "1" smd circle
			(at 0.40005 0 90)
			(size 0 0)
			(layers "B.Cu" "B.Mask" "B.Paste")
			(net "SCM_ROT_CPU_RST_R_N")
		)
		(pad "2" smd circle
			(at -0.40005 0 90)
			(size 0 0)
			(layers "B.Cu" "B.Mask" "B.Paste")
			(net "SCM_ROT_CPU_RST_N")
		)
	)
	(footprint ""
		(layer "B.Cu")
		(at 208.461356 -378.682504)
		(property "Reference" "PR2515"
			(at 0 0 0)
			(layer "B.SilkS")
			(hide yes)
			(effects
				(font
					(size 1.27 1.27)
				)
				(justify mirror)
			)
		)
		(property "Value" ""
			(at 0 0 0)
			(layer "B.Fab")
			(effects
				(font
					(size 1.27 1.27)
				)
				(justify mirror)
			)
		)
		(duplicate_pad_numbers_are_jumpers no)
		(fp_line
			(start -0.7874 -0.4064)
			(end -0.7874 0.4064)
			(stroke
				(width 0.1524)
				(type default)
			)
			(layer "B.SilkS")
		)
		(fp_line
			(start -0.7874 0.4064)
			(end 0.7874 0.4064)
			(stroke
				(width 0.1524)
				(type default)
			)
			(layer "B.SilkS")
		)
		(fp_line
			(start 0.7874 -0.4064)
			(end -0.7874 -0.4064)
			(stroke
				(width 0.1524)
				(type default)
			)
			(layer "B.SilkS")
		)
		(fp_line
			(start 0.7874 0.4064)
			(end 0.7874 -0.4064)
			(stroke
				(width 0.1524)
				(type default)
			)
			(layer "B.SilkS")
		)
		(fp_line
			(start -0.67945 -0.3048)
			(end -0.67945 0.3048)
			(stroke
				(width 0.1)
				(type default)
			)
			(layer "B.Fab")
		)
		(fp_line
			(start -0.67945 0.3048)
			(end -0.120396 0.3048)
			(stroke
				(width 0.1)
				(type default)
			)
			(layer "B.Fab")
		)
		(fp_line
			(start -0.12065 -0.3048)
			(end -0.67945 -0.3048)
			(stroke
				(width 0.1)
				(type default)
			)
			(layer "B.Fab")
		)
		(fp_line
			(start -0.12065 -0.2794)
			(end -0.12065 -0.3048)
			(stroke
				(width 0.1)
				(type default)
			)
			(layer "B.Fab")
		)
		(fp_line
			(start -0.120396 0.2794)
			(end 0.12065 0.2794)
			(stroke
				(width 0.1)
				(type default)
			)
			(layer "B.Fab")
		)
		(fp_line
			(start -0.120396 0.3048)
			(end -0.120396 0.2794)
			(stroke
				(width 0.1)
				(type default)
			)
			(layer "B.Fab")
		)
		(fp_line
			(start 0.12065 -0.305054)
			(end 0.12065 -0.2794)
			(stroke
				(width 0.1)
				(type default)
			)
			(layer "B.Fab")
		)
		(fp_line
			(start 0.12065 -0.2794)
			(end -0.12065 -0.2794)
			(stroke
				(width 0.1)
				(type default)
			)
			(layer "B.Fab")
		)
		(fp_line
			(start 0.12065 0.2794)
			(end 0.12065 0.3048)
			(stroke
				(width 0.1)
				(type default)
			)
			(layer "B.Fab")
		)
		(fp_line
			(start 0.12065 0.3048)
			(end 0.67945 0.3048)
			(stroke
				(width 0.1)
				(type default)
			)
			(layer "B.Fab")
		)
		(fp_line
			(start 0.67945 -0.305054)
			(end 0.12065 -0.305054)
			(stroke
				(width 0.1)
				(type default)
			)
			(layer "B.Fab")
		)
		(fp_line
			(start 0.67945 0.3048)
			(end 0.67945 -0.305054)
			(stroke
				(width 0.1)
				(type default)
			)
			(layer "B.Fab")
		)
		(pad "1" smd circle
			(at 0.40005 0 180)
			(size 0 0)
			(layers "B.Cu" "B.Mask" "B.Paste")
			(net "P12V_HSC_ADC_N")
		)
		(pad "2" smd circle
			(at -0.40005 0 180)
			(size 0 0)
			(layers "B.Cu" "B.Mask" "B.Paste")
			(net "P12V_HSC_SENSE2_R1_N")
		)
	)
)
